# S9S_MB_2U (Grand Teton) — schematic netlist excerpt (pin names and nets, part order shuffled) for the footprints in the layout excerpt that follows; sources: Cadence DE-HDL packaged netlist, KiCad conversion of 03242023_DA0F0TMBIJ0_F0T_Motherboard_J_brd_V01_OCP.brd

J37  SCONN168_ME1016810202011  IO  pkg CON_F168S2H7D_P0-6W2-95_LUH  page 153
  GND_A1  = GND
  GND_A2  = GND
  GND_A3  = GND
  GND_A4  = GND
  GND_A5  = GND
  GND_A6  = GND
  SMCLK  = SMB_OCP_SFF_3V3AUX_BUF_R_SCL
  SMDAT  = SMB_OCP_SFF_3V3AUX_BUF_R_SDA
  \smrst#\  = RST_SMB_OCP_SFF_N
  \prsnta#\  = OCP_SFF_PRSNTA_R_N
  \perst1#\  = RST_PERST1_OCP_SFF_N
  \prsntb2#\  = OCP_SFF_PRSNT2_R_N
  GND_A13  = GND
  REFCLKN1  = CLK_100M_OCP_SFF_1_DN
  REFCLKP1  = CLK_100M_OCP_SFF_1_DP
  GND_A16  = GND
  PERN0  = P5E_CPU0_PE1_RX_DN<0>
  PERP0  = P5E_CPU0_PE1_RX_DP<0>
  GND_A19  = GND
  PERN1  = P5E_CPU0_PE1_RX_DP<1>
  PERP1  = P5E_CPU0_PE1_RX_DN<1>
  GND_A22  = GND
  PERN2  = P5E_CPU0_PE1_RX_DP<2>
  PERP2  = P5E_CPU0_PE1_RX_DN<2>
  GND_A25  = GND
  PERN3  = P5E_CPU0_PE1_RX_DP<3>
  PERP3  = P5E_CPU0_PE1_RX_DN<3>
  GND_A28  = GND
  GND_A29  = GND
  PERN4  = P5E_CPU0_PE1_RX_DP<4>
  PERP4  = P5E_CPU0_PE1_RX_DN<4>
  GND_A32  = GND
  PERN5  = P5E_CPU0_PE1_RX_DP<5>
  PERP5  = P5E_CPU0_PE1_RX_DN<5>
  GND_A35  = GND
  PERN6  = P5E_CPU0_PE1_RX_DP<6>
  PERP6  = P5E_CPU0_PE1_RX_DN<6>
  GND_A38  = GND
  PERN7  = P5E_CPU0_PE1_RX_DP<7>
  PERP7  = P5E_CPU0_PE1_RX_DN<7>
  GND_A41  = GND
  \prsntb1#\  = OCP_SFF_PRSNT1_R_N
  GND_A43  = GND
  PERN8  = P5E_CPU0_PE1_RX_DP<8>
  PERP8  = P5E_CPU0_PE1_RX_DN<8>
  GND_A46  = GND
  PERN9  = P5E_CPU0_PE1_RX_DP<9>
  PERP9  = P5E_CPU0_PE1_RX_DN<9>
  GND_A49  = GND
  PERN10  = P5E_CPU0_PE1_RX_DP<10>
  PERP10  = P5E_CPU0_PE1_RX_DN<10>
  GND_A52  = GND
  PERN11  = P5E_CPU0_PE1_RX_DP<11>
  PERP11  = P5E_CPU0_PE1_RX_DN<11>
  GND_A55  = GND
  PERN12  = P5E_CPU0_PE1_RX_DP<12>
  PERP12  = P5E_CPU0_PE1_RX_DN<12>
  GND_A58  = GND
  PERN13  = P5E_CPU0_PE1_RX_DP<13>
  PERP13  = P5E_CPU0_PE1_RX_DN<13>
  GND_A61  = GND
  PERN14  = P5E_CPU0_PE1_RX_DP<14>
  PERP14  = P5E_CPU0_PE1_RX_DN<14>
  GND_A64  = GND
  PERN15  = P5E_CPU0_PE1_RX_DP<15>
  PERP15  = P5E_CPU0_PE1_RX_DN<15>
  GND_A67  = GND
  USB_DATN  = OCP_SFF_USB2_3_DN
  USB_DATP  = OCP_SFF_USB2_3_DP
  \pwrbrk0#\  = OCP_SFF_PWRBRK_N
  \+12v_edge_b1\  = P12V_OCP_SFF
  \+12v_edge_b2\  = P12V_OCP_SFF
  \+12v_edge_b3\  = P12V_OCP_SFF
  \+12v_edge_b4\  = P12V_OCP_SFF
  \+12v_edge_b5\  = P12V_OCP_SFF
  \+12v_edge_b6\  = P12V_OCP_SFF
  \bif0#\  = OCP_SFF_BIF0_R_N
  \bif1#\  = OCP_SFF_BIF1_R_N
  \bif2#\  = OCP_SFF_BIF2_R_N
  \perst0#\  = RST_PERST0_OCP_SFF_N
  \+3.3v_edge\  = P3V3_OCP_SFF
  AUX_PWR_EN  = OCP_SFF_AUX_PWR_EN_R
  GND_B13  = GND
  REFCLKN0  = CLK_100M_OCP_SFF_0_DN
  REFCLKP0  = CLK_100M_OCP_SFF_0_DP
  GND_B16  = GND
  PETN0  = P5E_CPU0_PE1_TX_C_DN<0>
  PETP0  = P5E_CPU0_PE1_TX_C_DP<0>
  GND_B19  = GND
  PETN1  = P5E_CPU0_PE1_TX_C_DN<1>
  PETP1  = P5E_CPU0_PE1_TX_C_DP<1>
  GND_B22  = GND
  PETN2  = P5E_CPU0_PE1_TX_C_DP<2>
  PETP2  = P5E_CPU0_PE1_TX_C_DN<2>
  GND_B25  = GND
  PETN3  = P5E_CPU0_PE1_TX_C_DN<3>
  PETP3  = P5E_CPU0_PE1_TX_C_DP<3>
  GND_B28  = GND
  GND_B29  = GND
  PETN4  = P5E_CPU0_PE1_TX_C_DP<4>
  PETP4  = P5E_CPU0_PE1_TX_C_DN<4>
  GND_B32  = GND
  PETN5  = P5E_CPU0_PE1_TX_C_DN<5>
  PETP5  = P5E_CPU0_PE1_TX_C_DP<5>
  GND_B35  = GND
  PETN6  = P5E_CPU0_PE1_TX_C_DP<6>
  PETP6  = P5E_CPU0_PE1_TX_C_DN<6>
  GND_B38  = GND
  PETN7  = P5E_CPU0_PE1_TX_C_DN<7>
  PETP7  = P5E_CPU0_PE1_TX_C_DP<7>
  GND_B41  = GND
  \prsntb0#\  = OCP_SFF_PRSNT0_R_N
  GND_B43  = GND
  PETN8  = P5E_CPU0_PE1_TX_C_DP<8>
  PETP8  = P5E_CPU0_PE1_TX_C_DN<8>
  GND_B46  = GND
  PETN9  = P5E_CPU0_PE1_TX_C_DN<9>
  PETP9  = P5E_CPU0_PE1_TX_C_DP<9>
  GND_B49  = GND
  PETN10  = P5E_CPU0_PE1_TX_C_DP<10>
  PETP10  = P5E_CPU0_PE1_TX_C_DN<10>
  GND_B52  = GND
  PETN11  = P5E_CPU0_PE1_TX_C_DN<11>
  PETP11  = P5E_CPU0_PE1_TX_C_DP<11>
  GND_B55  = GND
  PETN12  = P5E_CPU0_PE1_TX_C_DP<12>
  PETP12  = P5E_CPU0_PE1_TX_C_DN<12>
  GND_B58  = GND
  PETN13  = P5E_CPU0_PE1_TX_C_DN<13>
  PETP13  = P5E_CPU0_PE1_TX_C_DP<13>
  GND_B61  = GND
  PETN14  = P5E_CPU0_PE1_TX_C_DP<14>
  PETP14  = P5E_CPU0_PE1_TX_C_DN<14>
  GND_B64  = GND
  PETN15  = P5E_CPU0_PE1_TX_C_DN<15>
  PETP15  = P5E_CPU0_PE1_TX_C_DP<15>
  GND_B67  = GND
  RFU1_NC_B68  = TP_OCP_SFF_B68
  RFU1_NC_B69  = TP_OCP_SFF_B69
  \prsntb3#\  = OCP_SFF_PRSNT3_R_N
  G1  = GND
  G2  = GND
  G3  = GND
  G4  = GND
  G5  = GND
  \perst2#\  = RST_PERST2_OCP_SFF_N
  \perst3#\  = RST_PERST3_OCP_SFF_N
  \wake#\  = IRQ_LVC3_OCP_SFF_WAKE_N
  RBT_ARB_IN  = OCP_SFF_ISO1_RBT_ARB_IN
  RBT_ARB_OUT  = OCP_SFF_ISO2_RBT_ARB_OUT
  SLOT_ID1  = OCP_SFF_ID1
  RBT_TX_EN  = NCSI_OCP_SFF_TX_EN
  RBT_TXD1  = NCSI_OCP_SFF_TXD1
  RBT_TXD0  = NCSI_OCP_SFF_TXD0
  GND_OA10  = GND
  REFCLKN3  = CLK_100M_OCP_SFF_3_DN
  REFCLKP3  = CLK_100M_OCP_SFF_3_DP
  GND_OA13  = GND
  RBT_CLK_IN  = CLK_50M_NCSI_OCP_SFF_ISO
  NIC_PWR_GOOD  = FM_OCP_SFF_PWR_GOOD
  MAIN_PWR_EN  = OCP_SFF_MAIN_PWR_EN_R
  \ld#\  = SGPIO_OCP_SFF_LD_N
  DATA_IN  = SGPIO_OCP_SFF_DATAIN
  DATA_OUT  = SGPIO_OCP_SFF_DATAOUT
  CLK  = SGPIO_OCP_SFF_CLK
  SLOT_ID0  = OCP_SFF_ID0
  RBT_RXD1  = NCSI_OCP_SFF_RXD1
  RBT_RXD0  = NCSI_OCP_SFF_RXD0
  GND_OB10  = GND
  REFCLKN2  = CLK_100M_OCP_SFF_2_DN
  REFCLKP2  = CLK_100M_OCP_SFF_2_DP
  GND_OB13  = GND
  RBT_CRS_DV  = NCSI_OCP_SFF_CRS_DV

(kicad_pcb
	(version 20260206)
	(generator "pcbnew")
	(generator_version "10.0")
	(general
		(thickness 1.6)
		(legacy_teardrops no)
	)
	(paper "A4")
	(title_block
		(title "03242023_DA0F0TMBIJ0_F0T_Motherboard_J_brd_V01_OCP.brd")
		(comment 1 "Grand Teton / footprint 2414 of 6105 (J37), pads 1-45 of 175")
	)
	(layers
		(0 "F.Cu" signal "TOP")
		(4 "In1.Cu" signal "GND")
		(6 "In2.Cu" signal "IN1")
		(8 "In3.Cu" signal "GND1")
		(10 "In4.Cu" signal "IN2")
		(12 "In5.Cu" signal "GND2")
		(14 "In6.Cu" signal "IN3")
		(16 "In7.Cu" signal "GND3")
		(18 "In8.Cu" signal "VCC")
		(20 "In9.Cu" signal "VCC1")
		(22 "In10.Cu" signal "GND4")
		(24 "In11.Cu" signal "IN4")
		(26 "In12.Cu" signal "GND5")
		(28 "In13.Cu" signal "IN5")
		(30 "In14.Cu" signal "GND6")
		(32 "In15.Cu" signal "IN6")
		(34 "In16.Cu" signal "GND7")
		(2 "B.Cu" signal "BOTTOM")
		(9 "F.Adhes" user "F.Adhesive")
		(11 "B.Adhes" user "B.Adhesive")
		(13 "F.Paste" user "Package Geometry/Pastemask Top")
		(15 "B.Paste" user "Package Geometry/Pastemask Bottom")
		(5 "F.SilkS" user "Ref Des/Silkscreen Top")
		(7 "B.SilkS" user "Ref Des/Silkscreen Bottom")
		(1 "F.Mask" user "Board Geometry/Soldermask Top")
		(3 "B.Mask" user "Board Geometry/Soldermask Bottom")
		(17 "Dwgs.User" user "User.Drawings")
		(19 "Cmts.User" user "User.Comments")
		(21 "Eco1.User" user "User.Eco1")
		(23 "Eco2.User" user "User.Eco2")
		(25 "Edge.Cuts" user "Board Geometry/Outline")
		(27 "Margin" user)
		(31 "F.CrtYd" user "Package Geometry/Place Bound Top")
		(29 "B.CrtYd" user "Package Geometry/Place Bound Bottom")
		(35 "F.Fab" user "Ref Des/Assembly Top")
		(33 "B.Fab" user "Ref Des/Assembly Bottom")
	)
	(footprint ""
		(layer "F.Cu")
		(at 421.901874 -5.569966 -90)
		(property "Reference" "J37"
			(at -16.985996 31.63951 0)
			(unlocked yes)
			(layer "F.SilkS")
			(effects
				(font
					(size 0.7874 0.5842)
					(thickness 0.1524)
				)
				(justify left)
			)
		)
		(property "Value" ""
			(at 0 0 270)
			(layer "F.Fab")
			(effects
				(font
					(size 1.27 1.27)
				)
			)
		)
		(duplicate_pad_numbers_are_jumpers no)
		(pad "" np_thru_hole circle
			(at -0.599948 -32.079946 180)
			(size 1.1176 1.1176)
			(drill 1.1176)
			(layers "*.Cu" "*.Mask")
			(clearance 0.381)
			(thermal_gap 0.381)
		)
		(pad "" np_thru_hole circle
			(at 0.40005 32.085026 180)
			(size 1.1176 1.1176)
			(drill 1.1176)
			(layers "*.Cu" "*.Mask")
			(clearance 0.381)
			(thermal_gap 0.381)
		)
		(pad "A1" smd rect
			(at -2.750058 -18.465038 180)
			(size 0.381 1.4478)
			(layers "F.Cu" "F.Mask" "F.Paste")
			(net "GND")
		)
		(pad "A2" smd rect
			(at -2.750058 -17.86509 180)
			(size 0.381 1.4478)
			(layers "F.Cu" "F.Mask" "F.Paste")
			(net "GND")
		)
		(pad "A3" smd rect
			(at -2.750058 -17.264888 180)
			(size 0.381 1.4478)
			(layers "F.Cu" "F.Mask" "F.Paste")
			(net "GND")
		)
		(pad "A4" smd rect
			(at -2.750058 -16.66494 180)
			(size 0.381 1.4478)
			(layers "F.Cu" "F.Mask" "F.Paste")
			(net "GND")
		)
		(pad "A5" smd rect
			(at -2.750058 -16.064992 180)
			(size 0.381 1.4478)
			(layers "F.Cu" "F.Mask" "F.Paste")
			(net "GND")
		)
		(pad "A6" smd rect
			(at -2.750058 -15.465044 180)
			(size 0.381 1.4478)
			(layers "F.Cu" "F.Mask" "F.Paste")
			(net "GND")
		)
		(pad "A7" smd rect
			(at -2.750058 -14.865096 180)
			(size 0.381 1.4478)
			(layers "F.Cu" "F.Mask" "F.Paste")
			(net "SMB_OCP_SFF_3V3AUX_BUF_R_SCL")
		)
		(pad "A8" smd rect
			(at -2.750058 -14.264894 180)
			(size 0.381 1.4478)
			(layers "F.Cu" "F.Mask" "F.Paste")
			(net "SMB_OCP_SFF_3V3AUX_BUF_R_SDA")
		)
		(pad "A9" smd rect
			(at -2.750058 -13.664946 180)
			(size 0.381 1.4478)
			(layers "F.Cu" "F.Mask" "F.Paste")
			(net "RST_SMB_OCP_SFF_N")
		)
		(pad "A10" smd rect
			(at -2.750058 -13.064998 180)
			(size 0.381 1.4478)
			(layers "F.Cu" "F.Mask" "F.Paste")
			(net "OCP_SFF_PRSNTA_R_N")
		)
		(pad "A11" smd rect
			(at -2.750058 -12.46505 180)
			(size 0.381 1.4478)
			(layers "F.Cu" "F.Mask" "F.Paste")
			(net "RST_PERST1_OCP_SFF_N")
		)
		(pad "A12" smd rect
			(at -2.750058 -11.865102 180)
			(size 0.381 1.4478)
			(layers "F.Cu" "F.Mask" "F.Paste")
			(net "OCP_SFF_PRSNT2_R_N")
		)
		(pad "A13" smd rect
			(at -2.750058 -11.2649 180)
			(size 0.381 1.4478)
			(layers "F.Cu" "F.Mask" "F.Paste")
			(net "GND")
		)
		(pad "A14" smd rect
			(at -2.750058 -10.664952 180)
			(size 0.381 1.4478)
			(layers "F.Cu" "F.Mask" "F.Paste")
			(net "CLK_100M_OCP_SFF_1_DN")
		)
		(pad "A15" smd rect
			(at -2.750058 -10.065004 180)
			(size 0.381 1.4478)
			(layers "F.Cu" "F.Mask" "F.Paste")
			(net "CLK_100M_OCP_SFF_1_DP")
		)
		(pad "A16" smd rect
			(at -2.750058 -9.465056 180)
			(size 0.381 1.4478)
			(layers "F.Cu" "F.Mask" "F.Paste")
			(net "GND")
		)
		(pad "A17" smd rect
			(at -2.750058 -8.865108 180)
			(size 0.381 1.4478)
			(layers "F.Cu" "F.Mask" "F.Paste")
			(net "P5E_CPU0_PE1_RX_DN<0>")
		)
		(pad "A18" smd rect
			(at -2.750058 -8.264906 180)
			(size 0.381 1.4478)
			(layers "F.Cu" "F.Mask" "F.Paste")
			(net "P5E_CPU0_PE1_RX_DP<0>")
		)
		(pad "A19" smd rect
			(at -2.750058 -7.664958 180)
			(size 0.381 1.4478)
			(layers "F.Cu" "F.Mask" "F.Paste")
			(net "GND")
		)
		(pad "A20" smd rect
			(at -2.750058 -7.06501 180)
			(size 0.381 1.4478)
			(layers "F.Cu" "F.Mask" "F.Paste")
			(net "P5E_CPU0_PE1_RX_DP<1>")
		)
		(pad "A21" smd rect
			(at -2.750058 -6.465062 180)
			(size 0.381 1.4478)
			(layers "F.Cu" "F.Mask" "F.Paste")
			(net "P5E_CPU0_PE1_RX_DN<1>")
		)
		(pad "A22" smd rect
			(at -2.750058 -5.865114 180)
			(size 0.381 1.4478)
			(layers "F.Cu" "F.Mask" "F.Paste")
			(net "GND")
		)
		(pad "A23" smd rect
			(at -2.750058 -5.264912 180)
			(size 0.381 1.4478)
			(layers "F.Cu" "F.Mask" "F.Paste")
			(net "P5E_CPU0_PE1_RX_DP<2>")
		)
		(pad "A24" smd rect
			(at -2.750058 -4.664964 180)
			(size 0.381 1.4478)
			(layers "F.Cu" "F.Mask" "F.Paste")
			(net "P5E_CPU0_PE1_RX_DN<2>")
		)
		(pad "A25" smd rect
			(at -2.750058 -4.065016 180)
			(size 0.381 1.4478)
			(layers "F.Cu" "F.Mask" "F.Paste")
			(net "GND")
		)
		(pad "A26" smd rect
			(at -2.750058 -3.465068 180)
			(size 0.381 1.4478)
			(layers "F.Cu" "F.Mask" "F.Paste")
			(net "P5E_CPU0_PE1_RX_DP<3>")
		)
		(pad "A27" smd rect
			(at -2.750058 -2.86512 180)
			(size 0.381 1.4478)
			(layers "F.Cu" "F.Mask" "F.Paste")
			(net "P5E_CPU0_PE1_RX_DN<3>")
		)
		(pad "A28" smd rect
			(at -2.750058 -2.264918 180)
			(size 0.381 1.4478)
			(layers "F.Cu" "F.Mask" "F.Paste")
			(net "GND")
		)
		(pad "A29" smd rect
			(at -2.750058 1.74498 180)
			(size 0.381 1.4478)
			(layers "F.Cu" "F.Mask" "F.Paste")
			(net "GND")
		)
		(pad "A30" smd rect
			(at -2.750058 2.344928 180)
			(size 0.381 1.4478)
			(layers "F.Cu" "F.Mask" "F.Paste")
			(net "P5E_CPU0_PE1_RX_DP<4>")
		)
		(pad "A31" smd rect
			(at -2.750058 2.944876 180)
			(size 0.381 1.4478)
			(layers "F.Cu" "F.Mask" "F.Paste")
			(net "P5E_CPU0_PE1_RX_DN<4>")
		)
		(pad "A32" smd rect
			(at -2.750058 3.545078 180)
			(size 0.381 1.4478)
			(layers "F.Cu" "F.Mask" "F.Paste")
			(net "GND")
		)
		(pad "A33" smd rect
			(at -2.750058 4.145026 180)
			(size 0.381 1.4478)
			(layers "F.Cu" "F.Mask" "F.Paste")
			(net "P5E_CPU0_PE1_RX_DP<5>")
		)
		(pad "A34" smd rect
			(at -2.750058 4.744974 180)
			(size 0.381 1.4478)
			(layers "F.Cu" "F.Mask" "F.Paste")
			(net "P5E_CPU0_PE1_RX_DN<5>")
		)
		(pad "A35" smd rect
			(at -2.750058 5.344922 180)
			(size 0.381 1.4478)
			(layers "F.Cu" "F.Mask" "F.Paste")
			(net "GND")
		)
		(pad "A36" smd rect
			(at -2.750058 5.945124 180)
			(size 0.381 1.4478)
			(layers "F.Cu" "F.Mask" "F.Paste")
			(net "P5E_CPU0_PE1_RX_DP<6>")
		)
		(pad "A37" smd rect
			(at -2.750058 6.545072 180)
			(size 0.381 1.4478)
			(layers "F.Cu" "F.Mask" "F.Paste")
			(net "P5E_CPU0_PE1_RX_DN<6>")
		)
		(pad "A38" smd rect
			(at -2.750058 7.14502 180)
			(size 0.381 1.4478)
			(layers "F.Cu" "F.Mask" "F.Paste")
			(net "GND")
		)
		(pad "A39" smd rect
			(at -2.750058 7.744968 180)
			(size 0.381 1.4478)
			(layers "F.Cu" "F.Mask" "F.Paste")
			(net "P5E_CPU0_PE1_RX_DP<7>")
		)
		(pad "A40" smd rect
			(at -2.750058 8.344916 180)
			(size 0.381 1.4478)
			(layers "F.Cu" "F.Mask" "F.Paste")
			(net "P5E_CPU0_PE1_RX_DN<7>")
		)
		(pad "A41" smd rect
			(at -2.750058 8.945118 180)
			(size 0.381 1.4478)
			(layers "F.Cu" "F.Mask" "F.Paste")
			(net "GND")
		)
		(pad "A42" smd rect
			(at -2.750058 9.545066 180)
			(size 0.381 1.4478)
			(layers "F.Cu" "F.Mask" "F.Paste")
			(net "OCP_SFF_PRSNT1_R_N")
		)
		(pad "A43" smd rect
			(at -2.750058 14.454886 180)
			(size 0.381 1.4478)
			(layers "F.Cu" "F.Mask" "F.Paste")
			(net "GND")
		)
	)
)
